(kicad_pcb
	(version 20260206)
	(generator "pcbnew")
	(generator_version "10.0")
	(general
		(thickness 1.6)
		(legacy_teardrops no)
	)
	(paper "A4")
	(title_block
		(title "Bryce Canyon_F.DPB_16315-1-OCP.brd")
		(comment 1 "Bryce Canyon / footprints 1896-1902 of 2223")
	)
	(layers
		(0 "F.Cu" signal "TOP")
		(4 "In1.Cu" signal "L2GND")
		(6 "In2.Cu" signal "L3")
		(8 "In3.Cu" signal "L4GND")
		(10 "In4.Cu" signal "L5")
		(12 "In5.Cu" signal "L6VCC")
		(14 "In6.Cu" signal "L7VCC")
		(16 "In7.Cu" signal "L8")
		(18 "In8.Cu" signal "L9GND")
		(20 "In9.Cu" signal "L10")
		(22 "In10.Cu" signal "L11GND")
		(2 "B.Cu" signal "BOTTOM")
		(9 "F.Adhes" user "F.Adhesive")
		(11 "B.Adhes" user "B.Adhesive")
		(13 "F.Paste" user "Package Geometry/Pastemask Top")
		(15 "B.Paste" user "Package Geometry/Pastemask Bottom")
		(5 "F.SilkS" user "Ref Des/Silkscreen Top")
		(7 "B.SilkS" user "Ref Des/Silkscreen Bottom")
		(1 "F.Mask" user "Board Geometry/Soldermask Top")
		(3 "B.Mask" user "Board Geometry/Soldermask Bottom")
		(17 "Dwgs.User" user "User.Drawings")
		(19 "Cmts.User" user "User.Comments")
		(21 "Eco1.User" user "User.Eco1")
		(23 "Eco2.User" user "User.Eco2")
		(25 "Edge.Cuts" user "Board Geometry/Outline")
		(27 "Margin" user)
		(31 "F.CrtYd" user "Package Geometry/Place Bound Top")
		(29 "B.CrtYd" user "Package Geometry/Place Bound Bottom")
		(35 "F.Fab" user "Ref Des/Assembly Top")
		(33 "B.Fab" user "Ref Des/Assembly Bottom")
	)
	(footprint ""
		(layer "F.Cu")
		(at 464.9089 -57.851294 90)
		(property "Reference" "C491"
			(at 0 0 90)
			(layer "F.SilkS")
			(hide yes)
			(effects
				(font
					(size 1.27 1.27)
				)
			)
		)
		(property "Value" "SCD033U25V2KX-GP"
			(at 1.1811 -2.7051 90)
			(unlocked yes)
			(layer "F.Fab")
			(hide yes)
			(effects
				(font
					(size 1.016 1.016)
					(thickness 0.1524)
				)
			)
		)
		(property "Device Type" "C402H22"
			(at 1.1811 -4.2291 90)
			(unlocked yes)
			(layer "F.Fab")
			(hide yes)
			(effects
				(font
					(size 1.016 1.016)
					(thickness 0.1524)
				)
			)
		)
		(duplicate_pad_numbers_are_jumpers no)
		(fp_rect
			(start -0.4318 0.9525)
			(end 0.4318 -0.9525)
			(stroke
				(width 0)
				(type default)
			)
			(fill no)
			(layer "F.CrtYd")
		)
		(fp_rect
			(start -0.4318 0.9525)
			(end 0.4318 -0.9525)
			(stroke
				(width 0)
				(type default)
			)
			(fill no)
			(layer "F.Fab")
		)
		(pad "1" smd custom
			(at 0 -0.4445 90)
			(size 0.1524 0.1524)
			(layers "F.Cu" "F.Mask" "F.Paste")
			(net "P12V_A")
			(options
				(clearance outline)
				(anchor circle)
			)
			(primitives
				(gr_poly
					(pts
						(arc
							(start 0.3048 -0.2032)
							(mid 0.275042 -0.275042)
							(end 0.2032 -0.3048)
						)
						(arc
							(start -0.2032 -0.3048)
							(mid -0.275042 -0.275042)
							(end -0.3048 -0.2032)
						)
						(arc
							(start -0.3048 0.2032)
							(mid -0.275042 0.275042)
							(end -0.2032 0.3048)
						)
						(arc
							(start 0.2032 0.3048)
							(mid 0.275042 0.275042)
							(end 0.3048 0.2032)
						)
					)
					(width 0)
					(fill yes)
				)
			)
		)
		(pad "2" smd custom
			(at 0 0.4445 90)
			(size 0.1524 0.1524)
			(layers "F.Cu" "F.Mask" "F.Paste")
			(net "SW_HDD_N34")
			(options
				(clearance outline)
				(anchor circle)
			)
			(primitives
				(gr_poly
					(pts
						(arc
							(start 0.3048 -0.2032)
							(mid 0.275042 -0.275042)
							(end 0.2032 -0.3048)
						)
						(arc
							(start -0.2032 -0.3048)
							(mid -0.275042 -0.275042)
							(end -0.3048 -0.2032)
						)
						(arc
							(start -0.3048 0.2032)
							(mid -0.275042 0.275042)
							(end -0.2032 0.3048)
						)
						(arc
							(start 0.2032 0.3048)
							(mid 0.275042 0.275042)
							(end 0.3048 0.2032)
						)
					)
					(width 0)
					(fill yes)
				)
			)
		)
	)
	(footprint ""
		(layer "F.Cu")
		(at 99.228148 -295.064942 90)
		(property "Reference" "R180"
			(at 0 0 90)
			(layer "F.SilkS")
			(hide yes)
			(effects
				(font
					(size 1.27 1.27)
				)
			)
		)
		(property "Value" "220R3F-1-GP"
			(at -0.0254 -2.5146 90)
			(unlocked yes)
			(layer "F.Fab")
			(hide yes)
			(effects
				(font
					(size 1.016 1.016)
					(thickness 0.1524)
				)
			)
		)
		(property "Device Type" "R603H22"
			(at -0.0254 -4.0386 90)
			(unlocked yes)
			(layer "F.Fab")
			(hide yes)
			(effects
				(font
					(size 1.016 1.016)
					(thickness 0.1524)
				)
			)
		)
		(duplicate_pad_numbers_are_jumpers no)
		(fp_line
			(start 0.2032 0)
			(end 0.4826 0)
			(stroke
				(width 0.2032)
				(type default)
			)
			(layer "F.SilkS")
		)
		(fp_line
			(start -0.4826 0)
			(end -0.2032 0)
			(stroke
				(width 0.2032)
				(type default)
			)
			(layer "F.SilkS")
		)
		(fp_rect
			(start -0.5842 1.3335)
			(end 0.5842 -1.3335)
			(stroke
				(width 0)
				(type default)
			)
			(fill no)
			(layer "F.CrtYd")
		)
		(fp_rect
			(start -0.5842 1.3335)
			(end 0.5842 -1.3335)
			(stroke
				(width 0)
				(type default)
			)
			(fill no)
			(layer "F.Fab")
		)
		(pad "1" smd custom
			(at 0 -0.762 90)
			(size 0.2159 0.2159)
			(layers "F.Cu" "F.Mask" "F.Paste")
			(net "HDD_PRSNT_2")
			(options
				(clearance outline)
				(anchor circle)
			)
			(primitives
				(gr_poly
					(pts
						(arc
							(start -0.3302 -0.4318)
							(mid -0.402042 -0.402042)
							(end -0.4318 -0.3302)
						)
						(arc
							(start -0.4318 0.3302)
							(mid -0.402042 0.402042)
							(end -0.3302 0.4318)
						)
						(arc
							(start 0.3302 0.4318)
							(mid 0.402042 0.402042)
							(end 0.4318 0.3302)
						)
						(arc
							(start 0.4318 -0.3302)
							(mid 0.402042 -0.402042)
							(end 0.3302 -0.4318)
						)
					)
					(width 0)
					(fill yes)
				)
			)
		)
		(pad "2" smd custom
			(at 0 0.762 90)
			(size 0.2159 0.2159)
			(layers "F.Cu" "F.Mask" "F.Paste")
			(net "DRIVE_A_2_INS")
			(options
				(clearance outline)
				(anchor circle)
			)
			(primitives
				(gr_poly
					(pts
						(arc
							(start -0.3302 -0.4318)
							(mid -0.402042 -0.402042)
							(end -0.4318 -0.3302)
						)
						(arc
							(start -0.4318 0.3302)
							(mid -0.402042 0.402042)
							(end -0.3302 0.4318)
						)
						(arc
							(start 0.3302 0.4318)
							(mid 0.402042 0.402042)
							(end 0.4318 0.3302)
						)
						(arc
							(start 0.4318 -0.3302)
							(mid 0.402042 -0.402042)
							(end 0.3302 -0.4318)
						)
					)
					(width 0)
					(fill yes)
				)
			)
		)
	)
	(footprint ""
		(layer "F.Cu")
		(at 367.338102 -42.585894 180)
		(property "Reference" "R853"
			(at 0 0 180)
			(layer "F.SilkS")
			(hide yes)
			(effects
				(font
					(size 1.27 1.27)
				)
			)
		)
		(property "Value" "0R2J-2-GP"
			(at 0.064008 -3.993896 180)
			(unlocked yes)
			(layer "F.Fab")
			(hide yes)
			(effects
				(font
					(size 1.016 1.016)
					(thickness 0.1524)
				)
			)
		)
		(property "Device Type" "R402H16"
			(at 0.064008 -5.517896 180)
			(unlocked yes)
			(layer "F.Fab")
			(hide yes)
			(effects
				(font
					(size 1.016 1.016)
					(thickness 0.1524)
				)
			)
		)
		(duplicate_pad_numbers_are_jumpers no)
		(fp_line
			(start 0.508 -0.9398)
			(end -0.508 -0.9398)
			(stroke
				(width 0.1524)
				(type default)
			)
			(layer "F.SilkS")
		)
		(fp_line
			(start -0.508 -0.9398)
			(end -0.508 0.9398)
			(stroke
				(width 0.1524)
				(type default)
			)
			(layer "F.SilkS")
		)
		(fp_rect
			(start -0.508 0.9398)
			(end 0.508 -0.9398)
			(stroke
				(width 0)
				(type default)
			)
			(fill no)
			(layer "F.CrtYd")
		)
		(fp_rect
			(start -0.508 0.9398)
			(end 0.508 -0.9398)
			(stroke
				(width 0)
				(type default)
			)
			(fill no)
			(layer "F.Fab")
		)
		(pad "1" smd custom
			(at 0 -0.4445 180)
			(size 0.1397 0.1397)
			(layers "F.Cu" "F.Mask" "F.Paste")
			(net "DRIVE_A_31_PWR")
			(options
				(clearance outline)
				(anchor circle)
			)
			(primitives
				(gr_poly
					(pts
						(arc
							(start -0.1778 -0.2794)
							(mid -0.249642 -0.249642)
							(end -0.2794 -0.1778)
						)
						(arc
							(start -0.2794 0.1778)
							(mid -0.249642 0.249642)
							(end -0.1778 0.2794)
						)
						(arc
							(start 0.1778 0.2794)
							(mid 0.249642 0.249642)
							(end 0.2794 0.1778)
						)
						(arc
							(start 0.2794 -0.1778)
							(mid 0.249642 -0.249642)
							(end 0.1778 -0.2794)
						)
					)
					(width 0)
					(fill yes)
				)
			)
		)
		(pad "2" smd custom
			(at 0 0.4445 180)
			(size 0.1397 0.1397)
			(layers "F.Cu" "F.Mask" "F.Paste")
			(net "SW_PWR_R_HDD31")
			(options
				(clearance outline)
				(anchor circle)
			)
			(primitives
				(gr_poly
					(pts
						(arc
							(start -0.1778 -0.2794)
							(mid -0.249642 -0.249642)
							(end -0.2794 -0.1778)
						)
						(arc
							(start -0.2794 0.1778)
							(mid -0.249642 0.249642)
							(end -0.1778 0.2794)
						)
						(arc
							(start 0.1778 0.2794)
							(mid 0.249642 0.249642)
							(end 0.2794 0.1778)
						)
						(arc
							(start 0.2794 -0.1778)
							(mid 0.249642 -0.249642)
							(end 0.1778 -0.2794)
						)
					)
					(width 0)
					(fill yes)
				)
			)
		)
	)
	(footprint ""
		(layer "F.Cu")
		(at 346.368116 -285.33471 90)
		(property "Reference" "R578"
			(at 0 0 90)
			(layer "F.SilkS")
			(hide yes)
			(effects
				(font
					(size 1.27 1.27)
				)
			)
		)
		(property "Value" "4K7R2J-2-GP"
			(at 0.064008 -3.993896 90)
			(unlocked yes)
			(layer "F.Fab")
			(hide yes)
			(effects
				(font
					(size 1.016 1.016)
					(thickness 0.1524)
				)
			)
		)
		(property "Device Type" "R402H16"
			(at 0.064008 -5.517896 90)
			(unlocked yes)
			(layer "F.Fab")
			(hide yes)
			(effects
				(font
					(size 1.016 1.016)
					(thickness 0.1524)
				)
			)
		)
		(duplicate_pad_numbers_are_jumpers no)
		(fp_line
			(start 0.508 -0.9398)
			(end -0.508 -0.9398)
			(stroke
				(width 0.1524)
				(type default)
			)
			(layer "F.SilkS")
		)
		(fp_line
			(start -0.508 -0.9398)
			(end -0.508 0.9398)
			(stroke
				(width 0.1524)
				(type default)
			)
			(layer "F.SilkS")
		)
		(fp_rect
			(start -0.508 0.9398)
			(end 0.508 -0.9398)
			(stroke
				(width 0)
				(type default)
			)
			(fill no)
			(layer "F.CrtYd")
		)
		(fp_rect
			(start -0.508 0.9398)
			(end 0.508 -0.9398)
			(stroke
				(width 0)
				(type default)
			)
			(fill no)
			(layer "F.Fab")
		)
		(pad "1" smd custom
			(at 0 -0.4445 90)
			(size 0.1397 0.1397)
			(layers "F.Cu" "F.Mask" "F.Paste")
			(net "DRIVE_B_31_ACT")
			(options
				(clearance outline)
				(anchor circle)
			)
			(primitives
				(gr_poly
					(pts
						(arc
							(start -0.1778 -0.2794)
							(mid -0.249642 -0.249642)
							(end -0.2794 -0.1778)
						)
						(arc
							(start -0.2794 0.1778)
							(mid -0.249642 0.249642)
							(end -0.1778 0.2794)
						)
						(arc
							(start 0.1778 0.2794)
							(mid 0.249642 0.249642)
							(end 0.2794 0.1778)
						)
						(arc
							(start 0.2794 -0.1778)
							(mid 0.249642 -0.249642)
							(end 0.1778 -0.2794)
						)
					)
					(width 0)
					(fill yes)
				)
			)
		)
		(pad "2" smd custom
			(at 0 0.4445 90)
			(size 0.1397 0.1397)
			(layers "F.Cu" "F.Mask" "F.Paste")
			(net "GND")
			(options
				(clearance outline)
				(anchor circle)
			)
			(primitives
				(gr_poly
					(pts
						(arc
							(start -0.1778 -0.2794)
							(mid -0.249642 -0.249642)
							(end -0.2794 -0.1778)
						)
						(arc
							(start -0.2794 0.1778)
							(mid -0.249642 0.249642)
							(end -0.1778 0.2794)
						)
						(arc
							(start 0.1778 0.2794)
							(mid 0.249642 0.249642)
							(end 0.2794 0.1778)
						)
						(arc
							(start 0.2794 -0.1778)
							(mid 0.249642 -0.249642)
							(end 0.1778 -0.2794)
						)
					)
					(width 0)
					(fill yes)
				)
			)
		)
	)
	(footprint ""
		(layer "F.Cu")
		(at 257.173476 -261.35076 180)
		(property "Reference" "R53"
			(at 0 0 180)
			(layer "F.SilkS")
			(hide yes)
			(effects
				(font
					(size 1.27 1.27)
				)
			)
		)
		(property "Value" "4K7R2F-GP"
			(at 0.064008 -3.993896 180)
			(unlocked yes)
			(layer "F.Fab")
			(hide yes)
			(effects
				(font
					(size 1.016 1.016)
					(thickness 0.1524)
				)
			)
		)
		(property "Device Type" "R402H16"
			(at 0.064008 -5.517896 180)
			(unlocked yes)
			(layer "F.Fab")
			(hide yes)
			(effects
				(font
					(size 1.016 1.016)
					(thickness 0.1524)
				)
			)
		)
		(duplicate_pad_numbers_are_jumpers no)
		(fp_line
			(start 0.508 -0.9398)
			(end -0.508 -0.9398)
			(stroke
				(width 0.1524)
				(type default)
			)
			(layer "F.SilkS")
		)
		(fp_line
			(start -0.508 -0.9398)
			(end -0.508 0.9398)
			(stroke
				(width 0.1524)
				(type default)
			)
			(layer "F.SilkS")
		)
		(fp_rect
			(start -0.508 0.9398)
			(end 0.508 -0.9398)
			(stroke
				(width 0)
				(type default)
			)
			(fill no)
			(layer "F.CrtYd")
		)
		(fp_rect
			(start -0.508 0.9398)
			(end 0.508 -0.9398)
			(stroke
				(width 0)
				(type default)
			)
			(fill no)
			(layer "F.Fab")
		)
		(pad "1" smd custom
			(at 0 -0.4445 180)
			(size 0.1397 0.1397)
			(layers "F.Cu" "F.Mask" "F.Paste")
			(net "IO_EXP6_A0")
			(options
				(clearance outline)
				(anchor circle)
			)
			(primitives
				(gr_poly
					(pts
						(arc
							(start -0.1778 -0.2794)
							(mid -0.249642 -0.249642)
							(end -0.2794 -0.1778)
						)
						(arc
							(start -0.2794 0.1778)
							(mid -0.249642 0.249642)
							(end -0.1778 0.2794)
						)
						(arc
							(start 0.1778 0.2794)
							(mid 0.249642 0.249642)
							(end 0.2794 0.1778)
						)
						(arc
							(start 0.2794 -0.1778)
							(mid 0.249642 -0.249642)
							(end 0.1778 -0.2794)
						)
					)
					(width 0)
					(fill yes)
				)
			)
		)
		(pad "2" smd custom
			(at 0 0.4445 180)
			(size 0.1397 0.1397)
			(layers "F.Cu" "F.Mask" "F.Paste")
			(net "GND")
			(options
				(clearance outline)
				(anchor circle)
			)
			(primitives
				(gr_poly
					(pts
						(arc
							(start -0.1778 -0.2794)
							(mid -0.249642 -0.249642)
							(end -0.2794 -0.1778)
						)
						(arc
							(start -0.2794 0.1778)
							(mid -0.249642 0.249642)
							(end -0.1778 0.2794)
						)
						(arc
							(start 0.1778 0.2794)
							(mid 0.249642 0.249642)
							(end 0.2794 0.1778)
						)
						(arc
							(start 0.2794 -0.1778)
							(mid 0.249642 -0.249642)
							(end 0.1778 -0.2794)
						)
					)
					(width 0)
					(fill yes)
				)
			)
		)
	)
	(footprint ""
		(layer "F.Cu")
		(at 132.201666 -142.675102)
		(property "Reference" "R1294"
			(at 0 0 0)
			(layer "F.SilkS")
			(hide yes)
			(effects
				(font
					(size 1.27 1.27)
				)
			)
		)
		(property "Value" "3K3R3F-GP"
			(at -0.0254 -2.5146 0)
			(unlocked yes)
			(layer "F.Fab")
			(hide yes)
			(effects
				(font
					(size 1.016 1.016)
					(thickness 0.1524)
				)
			)
		)
		(property "Device Type" "R603H22"
			(at -0.0254 -4.0386 0)
			(unlocked yes)
			(layer "F.Fab")
			(hide yes)
			(effects
				(font
					(size 1.016 1.016)
					(thickness 0.1524)
				)
			)
		)
		(duplicate_pad_numbers_are_jumpers no)
		(fp_line
			(start -0.4826 0)
			(end -0.2032 0)
			(stroke
				(width 0.2032)
				(type default)
			)
			(layer "F.SilkS")
		)
		(fp_line
			(start 0.2032 0)
			(end 0.4826 0)
			(stroke
				(width 0.2032)
				(type default)
			)
			(layer "F.SilkS")
		)
		(fp_rect
			(start -0.5842 1.3335)
			(end 0.5842 -1.3335)
			(stroke
				(width 0)
				(type default)
			)
			(fill no)
			(layer "F.CrtYd")
		)
		(fp_rect
			(start -0.5842 1.3335)
			(end 0.5842 -1.3335)
			(stroke
				(width 0)
				(type default)
			)
			(fill no)
			(layer "F.Fab")
		)
		(pad "1" smd custom
			(at 0 -0.762)
			(size 0.2159 0.2159)
			(layers "F.Cu" "F.Mask" "F.Paste")
			(net "P12V_A")
			(options
				(clearance outline)
				(anchor circle)
			)
			(primitives
				(gr_poly
					(pts
						(arc
							(start -0.3302 -0.4318)
							(mid -0.402042 -0.402042)
							(end -0.4318 -0.3302)
						)
						(arc
							(start -0.4318 0.3302)
							(mid -0.402042 0.402042)
							(end -0.3302 0.4318)
						)
						(arc
							(start 0.3302 0.4318)
							(mid 0.402042 0.402042)
							(end 0.4318 0.3302)
						)
						(arc
							(start 0.4318 -0.3302)
							(mid 0.402042 -0.402042)
							(end 0.3302 -0.4318)
						)
					)
					(width 0)
					(fill yes)
				)
			)
		)
		(pad "2" smd custom
			(at 0 0.762)
			(size 0.2159 0.2159)
			(layers "F.Cu" "F.Mask" "F.Paste")
			(net "VCCP_A")
			(options
				(clearance outline)
				(anchor circle)
			)
			(primitives
				(gr_poly
					(pts
						(arc
							(start -0.3302 -0.4318)
							(mid -0.402042 -0.402042)
							(end -0.4318 -0.3302)
						)
						(arc
							(start -0.4318 0.3302)
							(mid -0.402042 0.402042)
							(end -0.3302 0.4318)
						)
						(arc
							(start 0.3302 0.4318)
							(mid 0.402042 0.402042)
							(end 0.4318 0.3302)
						)
						(arc
							(start 0.4318 -0.3302)
							(mid 0.402042 -0.402042)
							(end 0.3302 -0.4318)
						)
					)
					(width 0)
					(fill yes)
				)
			)
		)
	)
	(footprint ""
		(layer "F.Cu")
		(at 146.884898 -285.285942 180)
		(property "Reference" "Q24"
			(at 0 0 180)
			(layer "F.SilkS")
			(hide yes)
			(effects
				(font
					(size 1.27 1.27)
				)
			)
		)
		(property "Value" "AO4406AL-GP"
			(at -3.707384 -1.5367 180)
			(unlocked yes)
			(layer "F.Fab")
			(hide yes)
			(effects
				(font
					(size 1.016 1.016)
					(thickness 0.1524)
				)
			)
		)
		(property "Device Type" "SOIC8H69"
			(at -3.707384 -3.0607 180)
			(unlocked yes)
			(layer "F.Fab")
			(hide yes)
			(effects
				(font
					(size 1.016 1.016)
					(thickness 0.1524)
				)
			)
		)
		(duplicate_pad_numbers_are_jumpers no)
		(fp_line
			(start 2.1336 1.4224)
			(end 2.1336 -1.4224)
			(stroke
				(width 0.1524)
				(type default)
			)
			(layer "F.SilkS")
		)
		(fp_line
			(start 2.1336 -1.4224)
			(end -2.7432 -1.4224)
			(stroke
				(width 0.1524)
				(type default)
			)
			(layer "F.SilkS")
		)
		(fp_line
			(start -2.1844 -0.0508)
			(end -2.7178 0.508)
			(stroke
				(width 0.1524)
				(type default)
			)
			(layer "F.SilkS")
		)
		(fp_line
			(start -2.6289 3.4417)
			(end -2.6289 1.4732)
			(stroke
				(width 0.381)
				(type default)
			)
			(layer "F.SilkS")
		)
		(fp_line
			(start -2.7178 -0.508)
			(end -2.1844 -0.0508)
			(stroke
				(width 0.1524)
				(type default)
			)
			(layer "F.SilkS")
		)
		(fp_line
			(start -2.7432 1.4224)
			(end 2.1336 1.4224)
			(stroke
				(width 0.1524)
				(type default)
			)
			(layer "F.SilkS")
		)
		(fp_line
			(start -2.7432 1.4224)
			(end -2.6416 1.4224)
			(stroke
				(width 0.1524)
				(type default)
			)
			(layer "F.SilkS")
		)
		(fp_line
			(start -2.7432 -1.4224)
			(end -2.7432 1.4224)
			(stroke
				(width 0.1524)
				(type default)
			)
			(layer "F.SilkS")
		)
		(fp_poly
			(pts
				(xy -2.2098 -1.4224) (xy -2.2098 1.4224) (xy 2.2098 1.4224) (xy 2.2098 -1.4224)
			)
			(stroke
				(width 0)
				(type default)
			)
			(fill yes)
			(layer "F.SilkS")
		)
		(fp_rect
			(start -2.450084 2.999994)
			(end 2.450084 -2.999994)
			(stroke
				(width 0)
				(type default)
			)
			(fill no)
			(layer "F.CrtYd")
		)
		(fp_poly
			(pts
				(xy -2.8194 3.6322) (xy -2.8194 -3.6322) (xy 2.8194 -3.6322) (xy 2.8194 1.18364) (xy 2.450084 1.18364)
				(xy 2.450084 -2.999994) (xy -2.450084 -2.999994) (xy -2.450084 2.999994) (xy 2.450084 2.999994)
				(xy 2.450084 1.18618) (xy 2.8194 1.18618) (xy 2.8194 3.6322)
			)
			(stroke
				(width 0)
				(type default)
			)
			(fill no)
			(layer "F.CrtYd")
		)
		(fp_rect
			(start -2.8194 3.6322)
			(end 2.8194 -3.6322)
			(stroke
				(width 0)
				(type default)
			)
			(fill no)
			(layer "F.Fab")
		)
		(pad "1" smd rect
			(at -1.905 2.54 180)
			(size 0.635 1.651)
			(layers "F.Cu" "F.Mask" "F.Paste")
			(net "P5V_HDD4")
		)
		(pad "2" smd rect
			(at -0.635 2.54 180)
			(size 0.635 1.651)
			(layers "F.Cu" "F.Mask" "F.Paste")
			(net "P5V_HDD4")
		)
		(pad "3" smd rect
			(at 0.635 2.54 180)
			(size 0.635 1.651)
			(layers "F.Cu" "F.Mask" "F.Paste")
			(net "P5V_HDD4")
		)
		(pad "4" smd rect
			(at 1.905 2.54 180)
			(size 0.635 1.651)
			(layers "F.Cu" "F.Mask" "F.Paste")
			(net "SW_HDD_P4")
		)
		(pad "5" smd rect
			(at 1.905 -2.54 180)
			(size 0.635 1.651)
			(layers "F.Cu" "F.Mask" "F.Paste")
			(net "P5V_A_1")
		)
		(pad "6" smd rect
			(at 0.635 -2.54 180)
			(size 0.635 1.651)
			(layers "F.Cu" "F.Mask" "F.Paste")
			(net "P5V_A_1")
		)
		(pad "7" smd rect
			(at -0.635 -2.54 180)
			(size 0.635 1.651)
			(layers "F.Cu" "F.Mask" "F.Paste")
			(net "P5V_A_1")
		)
		(pad "8" smd rect
			(at -1.905 -2.54 180)
			(size 0.635 1.651)
			(layers "F.Cu" "F.Mask" "F.Paste")
			(net "P5V_A_1")
		)
	)
)
